(kicad_pcb
	(version 20260206)
	(generator "pcbnew")
	(generator_version "10.0")
	(general
		(thickness 1.6)
		(legacy_teardrops no)
	)
	(paper "A4")
	(title_block
		(title "03242023_DA0F0TMBIJ0_F0T_Motherboard_J_brd_V01_OCP.brd")
		(comment 1 "Grand Teton / footprints 5633-5638 of 6105")
	)
	(layers
		(0 "F.Cu" signal "TOP")
		(4 "In1.Cu" signal "GND")
		(6 "In2.Cu" signal "IN1")
		(8 "In3.Cu" signal "GND1")
		(10 "In4.Cu" signal "IN2")
		(12 "In5.Cu" signal "GND2")
		(14 "In6.Cu" signal "IN3")
		(16 "In7.Cu" signal "GND3")
		(18 "In8.Cu" signal "VCC")
		(20 "In9.Cu" signal "VCC1")
		(22 "In10.Cu" signal "GND4")
		(24 "In11.Cu" signal "IN4")
		(26 "In12.Cu" signal "GND5")
		(28 "In13.Cu" signal "IN5")
		(30 "In14.Cu" signal "GND6")
		(32 "In15.Cu" signal "IN6")
		(34 "In16.Cu" signal "GND7")
		(2 "B.Cu" signal "BOTTOM")
		(9 "F.Adhes" user "F.Adhesive")
		(11 "B.Adhes" user "B.Adhesive")
		(13 "F.Paste" user "Package Geometry/Pastemask Top")
		(15 "B.Paste" user "Package Geometry/Pastemask Bottom")
		(5 "F.SilkS" user "Ref Des/Silkscreen Top")
		(7 "B.SilkS" user "Ref Des/Silkscreen Bottom")
		(1 "F.Mask" user "Board Geometry/Soldermask Top")
		(3 "B.Mask" user "Board Geometry/Soldermask Bottom")
		(17 "Dwgs.User" user "User.Drawings")
		(19 "Cmts.User" user "User.Comments")
		(21 "Eco1.User" user "User.Eco1")
		(23 "Eco2.User" user "User.Eco2")
		(25 "Edge.Cuts" user "Board Geometry/Outline")
		(27 "Margin" user)
		(31 "F.CrtYd" user "Package Geometry/Place Bound Top")
		(29 "B.CrtYd" user "Package Geometry/Place Bound Bottom")
		(35 "F.Fab" user "Ref Des/Assembly Top")
		(33 "B.Fab" user "Ref Des/Assembly Bottom")
	)
	(footprint ""
		(layer "B.Cu")
		(at 80.812132 -58.416698 90)
		(property "Reference" "R3807"
			(at 0 0 90)
			(layer "B.SilkS")
			(hide yes)
			(effects
				(font
					(size 1.27 1.27)
				)
				(justify mirror)
			)
		)
		(property "Value" ""
			(at 0 0 90)
			(layer "B.Fab")
			(effects
				(font
					(size 1.27 1.27)
				)
				(justify mirror)
			)
		)
		(duplicate_pad_numbers_are_jumpers no)
		(fp_line
			(start 0.7874 -0.4064)
			(end -0.7874 -0.4064)
			(stroke
				(width 0.1524)
				(type default)
			)
			(layer "B.SilkS")
		)
		(fp_line
			(start -0.7874 -0.4064)
			(end -0.7874 0.4064)
			(stroke
				(width 0.1524)
				(type default)
			)
			(layer "B.SilkS")
		)
		(fp_line
			(start 0.7874 0.4064)
			(end 0.7874 -0.4064)
			(stroke
				(width 0.1524)
				(type default)
			)
			(layer "B.SilkS")
		)
		(fp_line
			(start -0.7874 0.4064)
			(end 0.7874 0.4064)
			(stroke
				(width 0.1524)
				(type default)
			)
			(layer "B.SilkS")
		)
		(fp_line
			(start 0.67945 -0.305054)
			(end 0.12065 -0.305054)
			(stroke
				(width 0.1)
				(type default)
			)
			(layer "B.Fab")
		)
		(fp_line
			(start 0.12065 -0.305054)
			(end 0.12065 -0.2794)
			(stroke
				(width 0.1)
				(type default)
			)
			(layer "B.Fab")
		)
		(fp_line
			(start -0.12065 -0.3048)
			(end -0.67945 -0.3048)
			(stroke
				(width 0.1)
				(type default)
			)
			(layer "B.Fab")
		)
		(fp_line
			(start -0.67945 -0.3048)
			(end -0.67945 0.3048)
			(stroke
				(width 0.1)
				(type default)
			)
			(layer "B.Fab")
		)
		(fp_line
			(start 0.12065 -0.2794)
			(end -0.12065 -0.2794)
			(stroke
				(width 0.1)
				(type default)
			)
			(layer "B.Fab")
		)
		(fp_line
			(start -0.12065 -0.2794)
			(end -0.12065 -0.3048)
			(stroke
				(width 0.1)
				(type default)
			)
			(layer "B.Fab")
		)
		(fp_line
			(start 0.12065 0.2794)
			(end 0.12065 0.3048)
			(stroke
				(width 0.1)
				(type default)
			)
			(layer "B.Fab")
		)
		(fp_line
			(start -0.120396 0.2794)
			(end 0.12065 0.2794)
			(stroke
				(width 0.1)
				(type default)
			)
			(layer "B.Fab")
		)
		(fp_line
			(start 0.67945 0.3048)
			(end 0.67945 -0.305054)
			(stroke
				(width 0.1)
				(type default)
			)
			(layer "B.Fab")
		)
		(fp_line
			(start 0.12065 0.3048)
			(end 0.67945 0.3048)
			(stroke
				(width 0.1)
				(type default)
			)
			(layer "B.Fab")
		)
		(fp_line
			(start -0.120396 0.3048)
			(end -0.120396 0.2794)
			(stroke
				(width 0.1)
				(type default)
			)
			(layer "B.Fab")
		)
		(fp_line
			(start -0.67945 0.3048)
			(end -0.120396 0.3048)
			(stroke
				(width 0.1)
				(type default)
			)
			(layer "B.Fab")
		)
		(pad "1" smd circle
			(at 0.40005 0 270)
			(size 0 0)
			(layers "B.Cu" "B.Mask" "B.Paste")
			(net "P3V3_OCP_UV_2_R1")
		)
		(pad "2" smd circle
			(at -0.40005 0 270)
			(size 0 0)
			(layers "B.Cu" "B.Mask" "B.Paste")
			(net "P3V3_OCP_UV_2")
		)
	)
	(footprint ""
		(layer "B.Cu")
		(at 416.02914 -169.700194)
		(property "Reference" "PC197_P0_1"
			(at 0 0 0)
			(layer "B.SilkS")
			(hide yes)
			(effects
				(font
					(size 1.27 1.27)
				)
				(justify mirror)
			)
		)
		(property "Value" ""
			(at 0 0 0)
			(layer "B.Fab")
			(effects
				(font
					(size 1.27 1.27)
				)
				(justify mirror)
			)
		)
		(duplicate_pad_numbers_are_jumpers no)
		(fp_line
			(start -1.524 -0.762)
			(end -1.524 0.762)
			(stroke
				(width 0.1524)
				(type default)
			)
			(layer "B.SilkS")
		)
		(fp_line
			(start -1.524 0.762)
			(end 1.524 0.762)
			(stroke
				(width 0.1524)
				(type default)
			)
			(layer "B.SilkS")
		)
		(fp_line
			(start 1.524 -0.762)
			(end -1.524 -0.762)
			(stroke
				(width 0.1524)
				(type default)
			)
			(layer "B.SilkS")
		)
		(fp_line
			(start 1.524 0.762)
			(end 1.524 -0.762)
			(stroke
				(width 0.1524)
				(type default)
			)
			(layer "B.SilkS")
		)
		(fp_line
			(start -1.1049 -0.724916)
			(end 1.1049 -0.724916)
			(stroke
				(width 0.1)
				(type default)
			)
			(layer "B.Fab")
		)
		(fp_line
			(start -1.1049 0.724916)
			(end -1.1049 -0.724916)
			(stroke
				(width 0.1)
				(type default)
			)
			(layer "B.Fab")
		)
		(fp_line
			(start 1.1049 -0.724916)
			(end 1.1049 0.724916)
			(stroke
				(width 0.1)
				(type default)
			)
			(layer "B.Fab")
		)
		(fp_line
			(start 1.1049 0.724916)
			(end -1.1049 0.724916)
			(stroke
				(width 0.1)
				(type default)
			)
			(layer "B.Fab")
		)
		(pad "1" smd rect
			(at 0.889 0)
			(size 1.016 1.27)
			(layers "B.Cu" "B.Mask" "B.Paste")
			(net "SW_P12V_PVCCINFAON_CPU0_FLT")
		)
		(pad "2" smd rect
			(at -0.889 0)
			(size 1.016 1.27)
			(layers "B.Cu" "B.Mask" "B.Paste")
			(net "GND")
		)
	)
	(footprint ""
		(layer "B.Cu")
		(at 243.001038 -101.447854 180)
		(property "Reference" "R1525"
			(at 0 0 0)
			(layer "B.SilkS")
			(hide yes)
			(effects
				(font
					(size 1.27 1.27)
				)
				(justify mirror)
			)
		)
		(property "Value" ""
			(at 0 0 0)
			(layer "B.Fab")
			(effects
				(font
					(size 1.27 1.27)
				)
				(justify mirror)
			)
		)
		(duplicate_pad_numbers_are_jumpers no)
		(fp_line
			(start 0.7874 0.4064)
			(end 0.7874 -0.4064)
			(stroke
				(width 0.1524)
				(type default)
			)
			(layer "B.SilkS")
		)
		(fp_line
			(start 0.7874 -0.4064)
			(end -0.7874 -0.4064)
			(stroke
				(width 0.1524)
				(type default)
			)
			(layer "B.SilkS")
		)
		(fp_line
			(start -0.7874 0.4064)
			(end 0.7874 0.4064)
			(stroke
				(width 0.1524)
				(type default)
			)
			(layer "B.SilkS")
		)
		(fp_line
			(start -0.7874 -0.4064)
			(end -0.7874 0.4064)
			(stroke
				(width 0.1524)
				(type default)
			)
			(layer "B.SilkS")
		)
		(fp_line
			(start 0.67945 0.3048)
			(end 0.67945 -0.305054)
			(stroke
				(width 0.1)
				(type default)
			)
			(layer "B.Fab")
		)
		(fp_line
			(start 0.67945 -0.305054)
			(end 0.12065 -0.305054)
			(stroke
				(width 0.1)
				(type default)
			)
			(layer "B.Fab")
		)
		(fp_line
			(start 0.12065 0.3048)
			(end 0.67945 0.3048)
			(stroke
				(width 0.1)
				(type default)
			)
			(layer "B.Fab")
		)
		(fp_line
			(start 0.12065 0.2794)
			(end 0.12065 0.3048)
			(stroke
				(width 0.1)
				(type default)
			)
			(layer "B.Fab")
		)
		(fp_line
			(start 0.12065 -0.2794)
			(end -0.12065 -0.2794)
			(stroke
				(width 0.1)
				(type default)
			)
			(layer "B.Fab")
		)
		(fp_line
			(start 0.12065 -0.305054)
			(end 0.12065 -0.2794)
			(stroke
				(width 0.1)
				(type default)
			)
			(layer "B.Fab")
		)
		(fp_line
			(start -0.120396 0.3048)
			(end -0.120396 0.2794)
			(stroke
				(width 0.1)
				(type default)
			)
			(layer "B.Fab")
		)
		(fp_line
			(start -0.120396 0.2794)
			(end 0.12065 0.2794)
			(stroke
				(width 0.1)
				(type default)
			)
			(layer "B.Fab")
		)
		(fp_line
			(start -0.12065 -0.2794)
			(end -0.12065 -0.3048)
			(stroke
				(width 0.1)
				(type default)
			)
			(layer "B.Fab")
		)
		(fp_line
			(start -0.12065 -0.3048)
			(end -0.67945 -0.3048)
			(stroke
				(width 0.1)
				(type default)
			)
			(layer "B.Fab")
		)
		(fp_line
			(start -0.67945 0.3048)
			(end -0.120396 0.3048)
			(stroke
				(width 0.1)
				(type default)
			)
			(layer "B.Fab")
		)
		(fp_line
			(start -0.67945 -0.3048)
			(end -0.67945 0.3048)
			(stroke
				(width 0.1)
				(type default)
			)
			(layer "B.Fab")
		)
		(pad "1" smd circle
			(at 0.40005 0)
			(size 0 0)
			(layers "B.Cu" "B.Mask" "B.Paste")
			(net "SMB_HOST_3V3AUX_SCL_R")
		)
		(pad "2" smd circle
			(at -0.40005 0)
			(size 0 0)
			(layers "B.Cu" "B.Mask" "B.Paste")
			(net "SMB_HOST_CLK_3V3AUX_SCL")
		)
	)
	(footprint ""
		(layer "B.Cu")
		(at 416.996626 -164.582602 180)
		(property "Reference" "PR380"
			(at 0 0 0)
			(layer "B.SilkS")
			(hide yes)
			(effects
				(font
					(size 1.27 1.27)
				)
				(justify mirror)
			)
		)
		(property "Value" ""
			(at 0 0 0)
			(layer "B.Fab")
			(effects
				(font
					(size 1.27 1.27)
				)
				(justify mirror)
			)
		)
		(duplicate_pad_numbers_are_jumpers no)
		(fp_line
			(start 0.7874 0.4064)
			(end 0.7874 -0.4064)
			(stroke
				(width 0.1524)
				(type default)
			)
			(layer "B.SilkS")
		)
		(fp_line
			(start 0.7874 -0.4064)
			(end -0.7874 -0.4064)
			(stroke
				(width 0.1524)
				(type default)
			)
			(layer "B.SilkS")
		)
		(fp_line
			(start -0.7874 0.4064)
			(end 0.7874 0.4064)
			(stroke
				(width 0.1524)
				(type default)
			)
			(layer "B.SilkS")
		)
		(fp_line
			(start -0.7874 -0.4064)
			(end -0.7874 0.4064)
			(stroke
				(width 0.1524)
				(type default)
			)
			(layer "B.SilkS")
		)
		(fp_line
			(start 0.67945 0.3048)
			(end 0.67945 -0.305054)
			(stroke
				(width 0.1)
				(type default)
			)
			(layer "B.Fab")
		)
		(fp_line
			(start 0.67945 -0.305054)
			(end 0.12065 -0.305054)
			(stroke
				(width 0.1)
				(type default)
			)
			(layer "B.Fab")
		)
		(fp_line
			(start 0.12065 0.3048)
			(end 0.67945 0.3048)
			(stroke
				(width 0.1)
				(type default)
			)
			(layer "B.Fab")
		)
		(fp_line
			(start 0.12065 0.2794)
			(end 0.12065 0.3048)
			(stroke
				(width 0.1)
				(type default)
			)
			(layer "B.Fab")
		)
		(fp_line
			(start 0.12065 -0.2794)
			(end -0.12065 -0.2794)
			(stroke
				(width 0.1)
				(type default)
			)
			(layer "B.Fab")
		)
		(fp_line
			(start 0.12065 -0.305054)
			(end 0.12065 -0.2794)
			(stroke
				(width 0.1)
				(type default)
			)
			(layer "B.Fab")
		)
		(fp_line
			(start -0.120396 0.3048)
			(end -0.120396 0.2794)
			(stroke
				(width 0.1)
				(type default)
			)
			(layer "B.Fab")
		)
		(fp_line
			(start -0.120396 0.2794)
			(end 0.12065 0.2794)
			(stroke
				(width 0.1)
				(type default)
			)
			(layer "B.Fab")
		)
		(fp_line
			(start -0.12065 -0.2794)
			(end -0.12065 -0.3048)
			(stroke
				(width 0.1)
				(type default)
			)
			(layer "B.Fab")
		)
		(fp_line
			(start -0.12065 -0.3048)
			(end -0.67945 -0.3048)
			(stroke
				(width 0.1)
				(type default)
			)
			(layer "B.Fab")
		)
		(fp_line
			(start -0.67945 0.3048)
			(end -0.120396 0.3048)
			(stroke
				(width 0.1)
				(type default)
			)
			(layer "B.Fab")
		)
		(fp_line
			(start -0.67945 -0.3048)
			(end -0.67945 0.3048)
			(stroke
				(width 0.1)
				(type default)
			)
			(layer "B.Fab")
		)
		(pad "1" smd circle
			(at 0.40005 0)
			(size 0 0)
			(layers "B.Cu" "B.Mask" "B.Paste")
			(net "PVCCFA_EHV_CPU0_PVCC")
		)
		(pad "2" smd circle
			(at -0.40005 0)
			(size 0 0)
			(layers "B.Cu" "B.Mask" "B.Paste")
			(net "PVCCD_HV_CPU0_VDD1")
		)
	)
	(footprint ""
		(layer "B.Cu")
		(at 185.755788 -109.775498 180)
		(property "Reference" "C1909"
			(at 0 0 0)
			(layer "B.SilkS")
			(hide yes)
			(effects
				(font
					(size 1.27 1.27)
				)
				(justify mirror)
			)
		)
		(property "Value" ""
			(at 0 0 0)
			(layer "B.Fab")
			(effects
				(font
					(size 1.27 1.27)
				)
				(justify mirror)
			)
		)
		(duplicate_pad_numbers_are_jumpers no)
		(fp_line
			(start 0.69215 0.2921)
			(end 0.69215 -0.2921)
			(stroke
				(width 0.1524)
				(type default)
			)
			(layer "B.SilkS")
		)
		(fp_line
			(start 0.69215 -0.2921)
			(end -0.69215 -0.2921)
			(stroke
				(width 0.1524)
				(type default)
			)
			(layer "B.SilkS")
		)
		(fp_line
			(start -0.69215 0.2921)
			(end 0.69215 0.2921)
			(stroke
				(width 0.1524)
				(type default)
			)
			(layer "B.SilkS")
		)
		(fp_line
			(start -0.69215 -0.2921)
			(end -0.69215 0.2921)
			(stroke
				(width 0.1524)
				(type default)
			)
			(layer "B.SilkS")
		)
		(fp_line
			(start 0.51435 0.2794)
			(end 0.51435 -0.2794)
			(stroke
				(width 0.1)
				(type default)
			)
			(layer "B.Fab")
		)
		(fp_line
			(start 0.51435 -0.2794)
			(end -0.51435 -0.2794)
			(stroke
				(width 0.1)
				(type default)
			)
			(layer "B.Fab")
		)
		(fp_line
			(start -0.51435 0.2794)
			(end 0.51435 0.2794)
			(stroke
				(width 0.1)
				(type default)
			)
			(layer "B.Fab")
		)
		(fp_line
			(start -0.51435 -0.2794)
			(end -0.51435 0.2794)
			(stroke
				(width 0.1)
				(type default)
			)
			(layer "B.Fab")
		)
		(pad "1" smd circle
			(at 0.40005 0)
			(size 0 0)
			(layers "B.Cu" "B.Mask" "B.Paste")
			(net "P3V3_AUX_FPGA_VCCIO2")
		)
		(pad "2" smd circle
			(at -0.40005 0)
			(size 0 0)
			(layers "B.Cu" "B.Mask" "B.Paste")
			(net "GND")
		)
		(zone
			(layer "B.Cu")
			(hatch none 0.5)
			(connect_pads
				(clearance 0)
			)
			(min_thickness 0.25)
			(keepout
				(tracks not_allowed)
				(vias allowed)
				(pads allowed)
				(copperpour not_allowed)
				(footprints allowed)
			)
			(placement
				(enabled no)
				(sheetname "")
			)
			(fill
				(thermal_gap 0.5)
				(thermal_bridge_width 0.5)
				(island_removal_mode 0)
			)
			(polygon
				(pts
					(xy 185.565288 -109.863128) (xy 185.656728 -109.921294) (xy 185.856118 -109.921294) (xy 185.946288 -109.863128)
					(xy 185.946288 -109.687868) (xy 185.856118 -109.629448) (xy 185.656728 -109.629448) (xy 185.565288 -109.687614)
				)
			)
		)
	)
	(footprint ""
		(layer "B.Cu")
		(at 135.81888 -9.362948 -90)
		(property "Reference" "R3776"
			(at 0 0 90)
			(layer "B.SilkS")
			(hide yes)
			(effects
				(font
					(size 1.27 1.27)
				)
				(justify mirror)
			)
		)
		(property "Value" ""
			(at 0 0 90)
			(layer "B.Fab")
			(effects
				(font
					(size 1.27 1.27)
				)
				(justify mirror)
			)
		)
		(duplicate_pad_numbers_are_jumpers no)
		(fp_line
			(start -0.7874 0.4064)
			(end 0.7874 0.4064)
			(stroke
				(width 0.1524)
				(type default)
			)
			(layer "B.SilkS")
		)
		(fp_line
			(start 0.7874 0.4064)
			(end 0.7874 -0.4064)
			(stroke
				(width 0.1524)
				(type default)
			)
			(layer "B.SilkS")
		)
		(fp_line
			(start -0.7874 -0.4064)
			(end -0.7874 0.4064)
			(stroke
				(width 0.1524)
				(type default)
			)
			(layer "B.SilkS")
		)
		(fp_line
			(start 0.7874 -0.4064)
			(end -0.7874 -0.4064)
			(stroke
				(width 0.1524)
				(type default)
			)
			(layer "B.SilkS")
		)
		(fp_line
			(start -0.67945 0.3048)
			(end -0.120396 0.3048)
			(stroke
				(width 0.1)
				(type default)
			)
			(layer "B.Fab")
		)
		(fp_line
			(start -0.120396 0.3048)
			(end -0.120396 0.2794)
			(stroke
				(width 0.1)
				(type default)
			)
			(layer "B.Fab")
		)
		(fp_line
			(start 0.12065 0.3048)
			(end 0.67945 0.3048)
			(stroke
				(width 0.1)
				(type default)
			)
			(layer "B.Fab")
		)
		(fp_line
			(start 0.67945 0.3048)
			(end 0.67945 -0.305054)
			(stroke
				(width 0.1)
				(type default)
			)
			(layer "B.Fab")
		)
		(fp_line
			(start -0.120396 0.2794)
			(end 0.12065 0.2794)
			(stroke
				(width 0.1)
				(type default)
			)
			(layer "B.Fab")
		)
		(fp_line
			(start 0.12065 0.2794)
			(end 0.12065 0.3048)
			(stroke
				(width 0.1)
				(type default)
			)
			(layer "B.Fab")
		)
		(fp_line
			(start -0.12065 -0.2794)
			(end -0.12065 -0.3048)
			(stroke
				(width 0.1)
				(type default)
			)
			(layer "B.Fab")
		)
		(fp_line
			(start 0.12065 -0.2794)
			(end -0.12065 -0.2794)
			(stroke
				(width 0.1)
				(type default)
			)
			(layer "B.Fab")
		)
		(fp_line
			(start -0.67945 -0.3048)
			(end -0.67945 0.3048)
			(stroke
				(width 0.1)
				(type default)
			)
			(layer "B.Fab")
		)
		(fp_line
			(start -0.12065 -0.3048)
			(end -0.67945 -0.3048)
			(stroke
				(width 0.1)
				(type default)
			)
			(layer "B.Fab")
		)
		(fp_line
			(start 0.12065 -0.305054)
			(end 0.12065 -0.2794)
			(stroke
				(width 0.1)
				(type default)
			)
			(layer "B.Fab")
		)
		(fp_line
			(start 0.67945 -0.305054)
			(end 0.12065 -0.305054)
			(stroke
				(width 0.1)
				(type default)
			)
			(layer "B.Fab")
		)
		(pad "1" smd circle
			(at 0.40005 0 90)
			(size 0 0)
			(layers "B.Cu" "B.Mask" "B.Paste")
			(net "FM_UARTSW_MSB_N")
		)
		(pad "2" smd circle
			(at -0.40005 0 90)
			(size 0 0)
			(layers "B.Cu" "B.Mask" "B.Paste")
			(net "FM_UARTSW_MSB_R")
		)
	)
)
